# SCM (Grand Teton) — schematic netlist excerpt (pin names and nets, part order shuffled) for the footprints in the layout excerpt that follows; sources: Cadence DE-HDL packaged netlist, KiCad conversion of 12092022_DA0F0TMDCD0_F0T_Management_Board_D_brd_V3_OCP.brd

C215  Q_CAP  10UF 6.3V 20% X6S  pkg C0402  page 32 : A = J7_P1 ; B = GND
R164  Q_RES  100 1% EMPTY  pkg 0402LF  page 27 : A = SPI_BMC_BOOT_MISO ; B = GND

(kicad_pcb
	(version 20260206)
	(generator "pcbnew")
	(generator_version "10.0")
	(general
		(thickness 1.6)
		(legacy_teardrops no)
	)
	(paper "A4")
	(title_block
		(title "12092022_DA0F0TMDCD0_F0T_Management_Board_D_brd_V3_OCP.brd")
		(comment 1 "Grand Teton / footprints 710-711 of 1440")
	)
	(layers
		(0 "F.Cu" signal "TOP")
		(4 "In1.Cu" signal "GND")
		(6 "In2.Cu" signal "IN1")
		(8 "In3.Cu" signal "GND1")
		(10 "In4.Cu" signal "IN2")
		(12 "In5.Cu" signal "VCC")
		(14 "In6.Cu" signal "VCC1")
		(16 "In7.Cu" signal "IN3")
		(18 "In8.Cu" signal "GND2")
		(20 "In9.Cu" signal "IN4")
		(22 "In10.Cu" signal "GND3")
		(2 "B.Cu" signal "BOTTOM")
		(9 "F.Adhes" user "F.Adhesive")
		(11 "B.Adhes" user "B.Adhesive")
		(13 "F.Paste" user "Package Geometry/Pastemask Top")
		(15 "B.Paste" user "Package Geometry/Pastemask Bottom")
		(5 "F.SilkS" user "Ref Des/Silkscreen Top")
		(7 "B.SilkS" user "Ref Des/Silkscreen Bottom")
		(1 "F.Mask" user "Board Geometry/Soldermask Top")
		(3 "B.Mask" user "Board Geometry/Soldermask Bottom")
		(17 "Dwgs.User" user "User.Drawings")
		(19 "Cmts.User" user "User.Comments")
		(21 "Eco1.User" user "User.Eco1")
		(23 "Eco2.User" user "User.Eco2")
		(25 "Edge.Cuts" user "Board Geometry/Outline")
		(27 "Margin" user)
		(31 "F.CrtYd" user "Package Geometry/Place Bound Top")
		(29 "B.CrtYd" user "Package Geometry/Place Bound Bottom")
		(35 "F.Fab" user "Ref Des/Assembly Top")
		(33 "B.Fab" user "Ref Des/Assembly Bottom")
	)
	(footprint ""
		(layer "F.Cu")
		(at 9.1694 -105.5878)
		(property "Reference" "C215"
			(at 0 0 0)
			(layer "F.SilkS")
			(hide yes)
			(effects
				(font
					(size 1.27 1.27)
				)
			)
		)
		(property "Value" ""
			(at 0 0 0)
			(layer "F.Fab")
			(effects
				(font
					(size 1.27 1.27)
				)
			)
		)
		(duplicate_pad_numbers_are_jumpers no)
		(fp_line
			(start -0.7874 -0.4064)
			(end 0.7874 -0.4064)
			(stroke
				(width 0.1524)
				(type default)
			)
			(layer "F.SilkS")
		)
		(fp_line
			(start -0.7874 0.4064)
			(end -0.7874 -0.4064)
			(stroke
				(width 0.1524)
				(type default)
			)
			(layer "F.SilkS")
		)
		(fp_line
			(start 0.7874 -0.4064)
			(end 0.7874 0.4064)
			(stroke
				(width 0.1524)
				(type default)
			)
			(layer "F.SilkS")
		)
		(fp_line
			(start 0.7874 0.4064)
			(end -0.7874 0.4064)
			(stroke
				(width 0.1524)
				(type default)
			)
			(layer "F.SilkS")
		)
		(fp_line
			(start -0.67945 -0.305054)
			(end -0.12065 -0.305054)
			(stroke
				(width 0.1)
				(type default)
			)
			(layer "F.Fab")
		)
		(fp_line
			(start -0.67945 0.3048)
			(end -0.67945 -0.305054)
			(stroke
				(width 0.1)
				(type default)
			)
			(layer "F.Fab")
		)
		(fp_line
			(start -0.12065 -0.305054)
			(end -0.12065 -0.2794)
			(stroke
				(width 0.1)
				(type default)
			)
			(layer "F.Fab")
		)
		(fp_line
			(start -0.12065 -0.2794)
			(end 0.12065 -0.2794)
			(stroke
				(width 0.1)
				(type default)
			)
			(layer "F.Fab")
		)
		(fp_line
			(start -0.12065 0.2794)
			(end -0.12065 0.3048)
			(stroke
				(width 0.1)
				(type default)
			)
			(layer "F.Fab")
		)
		(fp_line
			(start -0.12065 0.3048)
			(end -0.67945 0.3048)
			(stroke
				(width 0.1)
				(type default)
			)
			(layer "F.Fab")
		)
		(fp_line
			(start 0.120396 0.2794)
			(end -0.12065 0.2794)
			(stroke
				(width 0.1)
				(type default)
			)
			(layer "F.Fab")
		)
		(fp_line
			(start 0.120396 0.3048)
			(end 0.120396 0.2794)
			(stroke
				(width 0.1)
				(type default)
			)
			(layer "F.Fab")
		)
		(fp_line
			(start 0.12065 -0.3048)
			(end 0.67945 -0.3048)
			(stroke
				(width 0.1)
				(type default)
			)
			(layer "F.Fab")
		)
		(fp_line
			(start 0.12065 -0.2794)
			(end 0.12065 -0.3048)
			(stroke
				(width 0.1)
				(type default)
			)
			(layer "F.Fab")
		)
		(fp_line
			(start 0.67945 -0.3048)
			(end 0.67945 0.3048)
			(stroke
				(width 0.1)
				(type default)
			)
			(layer "F.Fab")
		)
		(fp_line
			(start 0.67945 0.3048)
			(end 0.120396 0.3048)
			(stroke
				(width 0.1)
				(type default)
			)
			(layer "F.Fab")
		)
		(pad "1" smd circle
			(at -0.40005 0)
			(size 0 0)
			(layers "F.Cu" "F.Mask" "F.Paste")
			(net "J7_P1")
		)
		(pad "2" smd circle
			(at 0.40005 0)
			(size 0 0)
			(layers "F.Cu" "F.Mask" "F.Paste")
			(net "GND")
		)
	)
	(footprint ""
		(layer "F.Cu")
		(at 60.579 -84.709 -90)
		(property "Reference" "R164"
			(at 0 0 270)
			(layer "F.SilkS")
			(hide yes)
			(effects
				(font
					(size 1.27 1.27)
				)
			)
		)
		(property "Value" ""
			(at 0 0 270)
			(layer "F.Fab")
			(effects
				(font
					(size 1.27 1.27)
				)
			)
		)
		(duplicate_pad_numbers_are_jumpers no)
		(fp_line
			(start -0.7874 0.4064)
			(end -0.7874 -0.4064)
			(stroke
				(width 0.1524)
				(type default)
			)
			(layer "F.SilkS")
		)
		(fp_line
			(start 0.7874 0.4064)
			(end -0.7874 0.4064)
			(stroke
				(width 0.1524)
				(type default)
			)
			(layer "F.SilkS")
		)
		(fp_line
			(start -0.7874 -0.4064)
			(end 0.7874 -0.4064)
			(stroke
				(width 0.1524)
				(type default)
			)
			(layer "F.SilkS")
		)
		(fp_line
			(start 0.7874 -0.4064)
			(end 0.7874 0.4064)
			(stroke
				(width 0.1524)
				(type default)
			)
			(layer "F.SilkS")
		)
		(fp_line
			(start -0.67945 0.3048)
			(end -0.67945 -0.305054)
			(stroke
				(width 0.1)
				(type default)
			)
			(layer "F.Fab")
		)
		(fp_line
			(start -0.12065 0.3048)
			(end -0.67945 0.3048)
			(stroke
				(width 0.1)
				(type default)
			)
			(layer "F.Fab")
		)
		(fp_line
			(start 0.120396 0.3048)
			(end 0.120396 0.2794)
			(stroke
				(width 0.1)
				(type default)
			)
			(layer "F.Fab")
		)
		(fp_line
			(start 0.67945 0.3048)
			(end 0.120396 0.3048)
			(stroke
				(width 0.1)
				(type default)
			)
			(layer "F.Fab")
		)
		(fp_line
			(start -0.12065 0.2794)
			(end -0.12065 0.3048)
			(stroke
				(width 0.1)
				(type default)
			)
			(layer "F.Fab")
		)
		(fp_line
			(start 0.120396 0.2794)
			(end -0.12065 0.2794)
			(stroke
				(width 0.1)
				(type default)
			)
			(layer "F.Fab")
		)
		(fp_line
			(start -0.12065 -0.2794)
			(end 0.12065 -0.2794)
			(stroke
				(width 0.1)
				(type default)
			)
			(layer "F.Fab")
		)
		(fp_line
			(start 0.12065 -0.2794)
			(end 0.12065 -0.3048)
			(stroke
				(width 0.1)
				(type default)
			)
			(layer "F.Fab")
		)
		(fp_line
			(start 0.12065 -0.3048)
			(end 0.67945 -0.3048)
			(stroke
				(width 0.1)
				(type default)
			)
			(layer "F.Fab")
		)
		(fp_line
			(start 0.67945 -0.3048)
			(end 0.67945 0.3048)
			(stroke
				(width 0.1)
				(type default)
			)
			(layer "F.Fab")
		)
		(fp_line
			(start -0.67945 -0.305054)
			(end -0.12065 -0.305054)
			(stroke
				(width 0.1)
				(type default)
			)
			(layer "F.Fab")
		)
		(fp_line
			(start -0.12065 -0.305054)
			(end -0.12065 -0.2794)
			(stroke
				(width 0.1)
				(type default)
			)
			(layer "F.Fab")
		)
		(pad "1" smd circle
			(at -0.40005 0 270)
			(size 0 0)
			(layers "F.Cu" "F.Mask" "F.Paste")
			(net "SPI_BMC_BOOT_MISO")
		)
		(pad "2" smd circle
			(at 0.40005 0 270)
			(size 0 0)
			(layers "F.Cu" "F.Mask" "F.Paste")
			(net "GND")
		)
	)
)
